#ISCELL
  mstr_misc dns *
  *
#ISCELL
  mstr_symbols intel_corp_bpage *
  *
#CELL
  mstr_vreg slg55021 *
  page198_i1
#ISCELL
  mstr_symbols gnd *
  page198_i12
#CELL
  mstr_vreg slg55021 *
  page198_i13
#ISCELL
  mstr_symbols p5v_stby *
  page198_i15
#ISCELL
  mstr_symbols gnd *
  page198_i18
#CELL
  mstr_vreg slg55021 *
  page198_i19
#ISCELL
  mstr_symbols p5v_stby *
  page198_i2
#ISCELL
  mstr_symbols p5v_stby *
  page198_i20
#ISCELL
  mstr_symbols p5v *
  page198_i21
#ISCELL
  mstr_symbols p12v *
  page198_i22
#ISCELL
  mstr_symbols p12v_stby *
  page198_i23
#CELL
  dev_discrete cap_a *
  page198_i24
#ISCELL
  mstr_symbols gnd *
  page198_i25
#CELL
  dev_discrete cap_a *
  page198_i26
#ISCELL
  mstr_symbols gnd *
  page198_i27
#CELL
  dev_discrete cap_a *
  page198_i28
#ISCELL
  mstr_symbols gnd *
  page198_i29
#ISCELL
  mstr_symbols gnd *
  page198_i3
#ISCELL
  mstr_standard offpage *
  page198_i32
#CELL
  dev_discrete cap_a *
  page198_i37
#CELL
  mstr_discrete cap *
  page198_i38
#ISCELL
  mstr_symbols gnd *
  page198_i39
#CELL
  mstr_discrete cap *
  page198_i40
#CELL
  dev_discrete cap_a *
  page198_i41
#ISCELL
  mstr_symbols gnd *
  page198_i42
#CELL
  dev_discrete cap_a *
  page198_i43
#CELL
  mstr_discrete cap *
  page198_i44
#ISCELL
  mstr_symbols gnd *
  page198_i45
#CELL
  dev_discrete cap_a *
  page198_i46
#CELL
  mstr_discrete cap *
  page198_i47
#ISCELL
  mstr_symbols gnd *
  page198_i48
#CELL
  dev_discrete cap_a *
  page198_i49
#CELL
  mstr_discrete cap *
  page198_i50
#ISCELL
  mstr_symbols gnd *
  page198_i51
#CELL
  dev_discrete cap_a *
  page198_i52
#CELL
  mstr_discrete cap *
  page198_i53
#ISCELL
  mstr_symbols gnd *
  page198_i54
#ISCELL
  mstr_standard offpage *
  page198_i58
#ISCELL
  mstr_standard offpage *
  page198_i59
#ISCELL
  mstr_symbols p3v3_stby *
  page198_i6
#CELL
  mstr_discrete cap *
  page198_i61
#ISCELL
  mstr_symbols gnd *
  page198_i63
#CELL
  dev_discrete cap_a *
  page198_i64
#ISCELL
  mstr_standard offpage *
  page198_i65
#ISCELL
  mstr_symbols gnd *
  page198_i66
#CELL
  dev_discrete cap_a *
  page198_i67
#ISCELL
  mstr_symbols p5v_stby *
  page198_i68
#CELL
  mstr_vreg slg55021 *
  page198_i69
#ISCELL
  mstr_symbols p3v3 *
  page198_i7
#ISCELL
  mstr_symbols gnd *
  page198_i70
#ISCELL
  mstr_symbols p12v_stby *
  page198_i73
#CELL
  mstr_discrete cap *
  page198_i74
#ISCELL
  mstr_symbols gnd *
  page198_i75
#CELL
  dev_discrete cap_a *
  page198_i76
#ISCELL
  mstr_symbols p12v_fan *
  page198_i77
#CELL
  mstr_discrete res *
  page198_i78
#ISCELL
  mstr_symbols p3v3_stby *
  page198_i79
#CELL
  mstr_discrete res *
  page198_i83
#ISCELL
  mstr_symbols gnd *
  page198_i84
#CELL
  mstr_discrete mosfet_n *
  page198_i85
#CELL
  mstr_discrete mosfet_n *
  page198_i86
#CELL
  mstr_discrete mosfet_n *
  page198_i87
#CELL
  mstr_discrete mosfet_n *
  page198_i88
#ISCELL
  mstr_symbols p5v_stby *
  page198_i9
